# BASEBOARD_FAB2 (Tioga Pass) — schematic netlist excerpt (pin names and nets, part order shuffled) for the footprints in the layout excerpt that follows; sources: Cadence DE-HDL packaged netlist, KiCad conversion of Wiwynn_Tioga_Pass_MB.brd

T1D1  TEST-PAD-12P-1-GP-U  pkg DISCRET-GB1  page 257
  DP  = L1_85OHM_5INCH_DP
  DN  = L1_85OHM_5INCH_DN
  GND(0)  = GND
  GND(1)  = GND
  GND(2)  = GND
  GND(3)  = GND
  GND(4)  = GND
  GND(5)  = GND
  GND(6)  = GND
  GND(7)  = GND
  GND(8)  = GND
  GND(9)  = GND

R4D35  RES  10.0K 1% EMPTY  pkg 0402  page 102 : A = P3V3_DB1200 ; B = FM_DB1200_SMB_SA0

(kicad_pcb
	(version 20260206)
	(generator "pcbnew")
	(generator_version "10.0")
	(general
		(thickness 1.6)
		(legacy_teardrops no)
	)
	(paper "A4")
	(title_block
		(title "Wiwynn_Tioga_Pass_MB.brd")
		(comment 1 "Tioga Pass / footprints 1548-1549 of 4770")
	)
	(layers
		(0 "F.Cu" signal "TOP")
		(4 "In1.Cu" signal "L2GND")
		(6 "In2.Cu" signal "L3")
		(8 "In3.Cu" signal "L4GND")
		(10 "In4.Cu" signal "L5")
		(12 "In5.Cu" signal "L6GND")
		(14 "In6.Cu" signal "L7VCC")
		(16 "In7.Cu" signal "L8VCC")
		(18 "In8.Cu" signal "L9GND")
		(20 "In9.Cu" signal "L10")
		(22 "In10.Cu" signal "L11GND")
		(24 "In11.Cu" signal "L12")
		(26 "In12.Cu" signal "L13GND")
		(2 "B.Cu" signal "BOTTOM")
		(9 "F.Adhes" user "F.Adhesive")
		(11 "B.Adhes" user "B.Adhesive")
		(13 "F.Paste" user "Package Geometry/Pastemask Top")
		(15 "B.Paste" user "Package Geometry/Pastemask Bottom")
		(5 "F.SilkS" user "Ref Des/Silkscreen Top")
		(7 "B.SilkS" user "Ref Des/Silkscreen Bottom")
		(1 "F.Mask" user "Board Geometry/Soldermask Top")
		(3 "B.Mask" user "Board Geometry/Soldermask Bottom")
		(17 "Dwgs.User" user "User.Drawings")
		(19 "Cmts.User" user "User.Comments")
		(21 "Eco1.User" user "User.Eco1")
		(23 "Eco2.User" user "User.Eco2")
		(25 "Edge.Cuts" user "Board Geometry/Outline")
		(27 "Margin" user)
		(31 "F.CrtYd" user "Package Geometry/Place Bound Top")
		(29 "B.CrtYd" user "Package Geometry/Place Bound Bottom")
		(35 "F.Fab" user "Ref Des/Assembly Top")
		(33 "B.Fab" user "Ref Des/Assembly Bottom")
	)
	(footprint ""
		(layer "F.Cu")
		(at 171.069 -74.041 180)
		(property "Reference" "R4D35"
			(at 0 0 180)
			(layer "F.SilkS")
			(hide yes)
			(effects
				(font
					(size 1.27 1.27)
				)
			)
		)
		(property "Value" ""
			(at 0 0 180)
			(layer "F.Fab")
			(effects
				(font
					(size 1.27 1.27)
				)
			)
		)
		(duplicate_pad_numbers_are_jumpers no)
		(fp_poly
			(pts
				(xy -0.2794 -0.1016) (xy 0.2794 -0.1016) (xy 0.2794 0.9906) (xy -0.2794 0.9906)
			)
			(stroke
				(width 0)
				(type default)
			)
			(fill no)
			(layer "F.CrtYd")
		)
		(fp_line
			(start 0.2794 0.9906)
			(end 0.2794 -0.1016)
			(stroke
				(width 0.1)
				(type default)
			)
			(layer "F.Fab")
		)
		(fp_line
			(start 0.2794 -0.1016)
			(end -0.2794 -0.1016)
			(stroke
				(width 0.1)
				(type default)
			)
			(layer "F.Fab")
		)
		(fp_line
			(start -0.2794 0.9906)
			(end 0.2794 0.9906)
			(stroke
				(width 0.1)
				(type default)
			)
			(layer "F.Fab")
		)
		(fp_line
			(start -0.2794 -0.1016)
			(end -0.2794 0.9906)
			(stroke
				(width 0.1)
				(type default)
			)
			(layer "F.Fab")
		)
		(pad "1" smd rect
			(at 0 0 180)
			(size 0.508 0.508)
			(layers "F.Cu" "F.Mask" "F.Paste")
			(net "P3V3_DB1200")
		)
		(pad "2" smd rect
			(at 0 0.889 180)
			(size 0.508 0.508)
			(layers "F.Cu" "F.Mask" "F.Paste")
			(net "FM_DB1200_SMB_SA0")
		)
		(zone
			(layer "F.Cu")
			(hatch none 0.5)
			(connect_pads
				(clearance 0)
			)
			(min_thickness 0.25)
			(keepout
				(tracks not_allowed)
				(vias allowed)
				(pads allowed)
				(copperpour not_allowed)
				(footprints allowed)
			)
			(placement
				(enabled no)
				(sheetname "")
			)
			(fill
				(thermal_gap 0.5)
				(thermal_bridge_width 0.5)
				(island_removal_mode 0)
			)
			(polygon
				(pts
					(xy 171.323 -74.676) (xy 170.815 -74.676) (xy 170.815 -74.295) (xy 171.323 -74.295)
				)
			)
		)
		(zone
			(layer "F.Cu")
			(hatch none 0.5)
			(connect_pads
				(clearance 0)
			)
			(min_thickness 0.25)
			(keepout
				(tracks allowed)
				(vias not_allowed)
				(pads allowed)
				(copperpour not_allowed)
				(footprints allowed)
			)
			(placement
				(enabled no)
				(sheetname "")
			)
			(fill
				(thermal_gap 0.5)
				(thermal_bridge_width 0.5)
				(island_removal_mode 0)
			)
			(polygon
				(pts
					(xy 171.323 -74.295) (xy 170.815 -74.295) (xy 170.815 -74.676) (xy 171.323 -74.676)
				)
			)
		)
	)
	(footprint ""
		(layer "F.Cu")
		(at 13.35024 -165.01618 -90)
		(property "Reference" "T1D1"
			(at 0 0 270)
			(layer "F.SilkS")
			(hide yes)
			(effects
				(font
					(size 1.27 1.27)
				)
			)
		)
		(property "Value" "*"
			(at -3.4036 -4.46405 270)
			(unlocked yes)
			(layer "F.Fab")
			(hide yes)
			(effects
				(font
					(size 0.889 0.889)
					(thickness 0.1524)
				)
			)
		)
		(property "Device Type" "TEST-PAD-12P-1-GP-U_DISCRET-GBA"
			(at -3.4036 -5.98805 270)
			(unlocked yes)
			(layer "F.Fab")
			(hide yes)
			(effects
				(font
					(size 0.889 0.889)
					(thickness 0.1524)
				)
			)
		)
		(duplicate_pad_numbers_are_jumpers no)
		(fp_line
			(start -2.3876 3.4798)
			(end -2.3876 -4.826)
			(stroke
				(width 0.1524)
				(type default)
			)
			(layer "F.SilkS")
		)
		(fp_line
			(start 2.3622 3.4798)
			(end -2.3876 3.4798)
			(stroke
				(width 0.1524)
				(type default)
			)
			(layer "F.SilkS")
		)
		(fp_line
			(start -2.3876 -4.826)
			(end 2.3622 -4.826)
			(stroke
				(width 0.1524)
				(type default)
			)
			(layer "F.SilkS")
		)
		(fp_line
			(start 2.3622 -4.826)
			(end 2.3622 3.4798)
			(stroke
				(width 0.1524)
				(type default)
			)
			(layer "F.SilkS")
		)
		(fp_rect
			(start -2.6416 3.7338)
			(end 2.6162 -5.08)
			(stroke
				(width 0)
				(type default)
			)
			(fill no)
			(layer "F.CrtYd")
		)
		(fp_rect
			(start -2.6416 3.7338)
			(end 2.6162 -5.08)
			(stroke
				(width 0)
				(type default)
			)
			(fill no)
			(layer "F.Fab")
		)
		(pad "1" smd circle
			(at 0.496824 -1.301496 270)
			(size 0.6604 0.6604)
			(layers "F.Cu" "F.Mask" "F.Paste")
			(net "L1_85OHM_5INCH_DP")
		)
		(pad "2" smd circle
			(at -0.503936 -1.301496 270)
			(size 0.6604 0.6604)
			(layers "F.Cu" "F.Mask" "F.Paste")
			(net "L1_85OHM_5INCH_DN")
		)
		(pad "3" smd custom
			(at -0.00889 0.370078 270)
			(size 0.74295 0.74295)
			(layers "F.Cu" "F.Mask" "F.Paste")
			(net "GND")
			(options
				(clearance outline)
				(anchor circle)
			)
			(primitives
				(gr_poly
					(pts
						(xy -2.1209 1.4859) (xy 2.1209 1.4859) (xy 2.1209 -1.4859) (xy 1.08585 -1.4859) (xy 1.08585 -0.4699)
						(xy -1.08585 -0.4699) (xy -1.08585 -1.4859) (xy -2.1209 -1.4859)
					)
					(width 0)
					(fill yes)
				)
			)
		)
		(pad "4" thru_hole circle
			(at 1.266444 -3.851656 270)
			(size 1.4478 1.4478)
			(drill 1.0414)
			(layers "*.Cu" "*.Mask")
			(remove_unused_layers no)
			(net "GND")
			(clearance 0.1524)
			(thermal_gap 0.1524)
		)
		(pad "5" thru_hole circle
			(at -1.273556 -3.851656 270)
			(size 1.4478 1.4478)
			(drill 1.0414)
			(layers "*.Cu" "*.Mask")
			(remove_unused_layers no)
			(net "GND")
			(clearance 0.1524)
			(thermal_gap 0.1524)
		)
		(pad "6" thru_hole circle
			(at 1.266444 2.498344 270)
			(size 1.4478 1.4478)
			(drill 1.0414)
			(layers "*.Cu" "*.Mask")
			(remove_unused_layers no)
			(net "GND")
			(clearance 0.1524)
			(thermal_gap 0.1524)
		)
		(pad "7" thru_hole circle
			(at -1.273556 2.498344 270)
			(size 1.4478 1.4478)
			(drill 1.0414)
			(layers "*.Cu" "*.Mask")
			(remove_unused_layers no)
			(net "GND")
			(clearance 0.1524)
			(thermal_gap 0.1524)
		)
		(pad "8" thru_hole circle
			(at 1.27 -0.4572 270)
			(size 0.7112 0.7112)
			(drill 0.4064)
			(layers "*.Cu" "*.Mask")
			(remove_unused_layers no)
			(net "GND")
			(clearance 0.1016)
			(thermal_gap 0.1016)
		)
		(pad "9" thru_hole circle
			(at 1.27 0.762 270)
			(size 0.7112 0.7112)
			(drill 0.4064)
			(layers "*.Cu" "*.Mask")
			(remove_unused_layers no)
			(net "GND")
			(clearance 0.1016)
			(thermal_gap 0.1016)
		)
		(pad "10" thru_hole circle
			(at -0.0254 0.762 270)
			(size 0.7112 0.7112)
			(drill 0.4064)
			(layers "*.Cu" "*.Mask")
			(remove_unused_layers no)
			(net "GND")
			(clearance 0.1016)
			(thermal_gap 0.1016)
		)
		(pad "11" thru_hole circle
			(at -1.27 0.762 270)
			(size 0.7112 0.7112)
			(drill 0.4064)
			(layers "*.Cu" "*.Mask")
			(remove_unused_layers no)
			(net "GND")
			(clearance 0.1016)
			(thermal_gap 0.1016)
		)
		(pad "12" thru_hole circle
			(at -1.27 -0.4572 270)
			(size 0.7112 0.7112)
			(drill 0.4064)
			(layers "*.Cu" "*.Mask")
			(remove_unused_layers no)
			(net "GND")
			(clearance 0.1016)
			(thermal_gap 0.1016)
		)
	)
)
